# SCM (Grand Teton) — schematic netlist excerpt (pin names and nets, part order shuffled) for the footprints in the layout excerpt that follows; sources: Cadence DE-HDL packaged netlist, KiCad conversion of 12092022_DA0F0TMDCD0_F0T_Management_Board_D_brd_V3_OCP.brd

C291  Q_CAP  0.1UF 25V 10% X7R  pkg 0402  page 53 : A = P2V5_AUX ; B = GND
R249  Q_RES  2.2K 5% CHIP  pkg 0402LF  page 27 : A = P3V3_AUX ; B = SMB_BMC_MM3_SDA

(kicad_pcb
	(version 20260206)
	(generator "pcbnew")
	(generator_version "10.0")
	(general
		(thickness 1.6)
		(legacy_teardrops no)
	)
	(paper "A4")
	(title_block
		(title "12092022_DA0F0TMDCD0_F0T_Management_Board_D_brd_V3_OCP.brd")
		(comment 1 "Grand Teton / footprints 501-502 of 1440")
	)
	(layers
		(0 "F.Cu" signal "TOP")
		(4 "In1.Cu" signal "GND")
		(6 "In2.Cu" signal "IN1")
		(8 "In3.Cu" signal "GND1")
		(10 "In4.Cu" signal "IN2")
		(12 "In5.Cu" signal "VCC")
		(14 "In6.Cu" signal "VCC1")
		(16 "In7.Cu" signal "IN3")
		(18 "In8.Cu" signal "GND2")
		(20 "In9.Cu" signal "IN4")
		(22 "In10.Cu" signal "GND3")
		(2 "B.Cu" signal "BOTTOM")
		(9 "F.Adhes" user "F.Adhesive")
		(11 "B.Adhes" user "B.Adhesive")
		(13 "F.Paste" user "Package Geometry/Pastemask Top")
		(15 "B.Paste" user "Package Geometry/Pastemask Bottom")
		(5 "F.SilkS" user "Ref Des/Silkscreen Top")
		(7 "B.SilkS" user "Ref Des/Silkscreen Bottom")
		(1 "F.Mask" user "Board Geometry/Soldermask Top")
		(3 "B.Mask" user "Board Geometry/Soldermask Bottom")
		(17 "Dwgs.User" user "User.Drawings")
		(19 "Cmts.User" user "User.Comments")
		(21 "Eco1.User" user "User.Eco1")
		(23 "Eco2.User" user "User.Eco2")
		(25 "Edge.Cuts" user "Board Geometry/Outline")
		(27 "Margin" user)
		(31 "F.CrtYd" user "Package Geometry/Place Bound Top")
		(29 "B.CrtYd" user "Package Geometry/Place Bound Bottom")
		(35 "F.Fab" user "Ref Des/Assembly Top")
		(33 "B.Fab" user "Ref Des/Assembly Bottom")
	)
	(footprint ""
		(layer "F.Cu")
		(at 49.80051 -30.867604 90)
		(property "Reference" "R249"
			(at 0 0 90)
			(layer "F.SilkS")
			(hide yes)
			(effects
				(font
					(size 1.27 1.27)
				)
			)
		)
		(property "Value" ""
			(at 0 0 90)
			(layer "F.Fab")
			(effects
				(font
					(size 1.27 1.27)
				)
			)
		)
		(duplicate_pad_numbers_are_jumpers no)
		(fp_line
			(start 0.7874 -0.4064)
			(end 0.7874 0.4064)
			(stroke
				(width 0.1524)
				(type default)
			)
			(layer "F.SilkS")
		)
		(fp_line
			(start -0.7874 -0.4064)
			(end 0.7874 -0.4064)
			(stroke
				(width 0.1524)
				(type default)
			)
			(layer "F.SilkS")
		)
		(fp_line
			(start 0.7874 0.4064)
			(end -0.7874 0.4064)
			(stroke
				(width 0.1524)
				(type default)
			)
			(layer "F.SilkS")
		)
		(fp_line
			(start -0.7874 0.4064)
			(end -0.7874 -0.4064)
			(stroke
				(width 0.1524)
				(type default)
			)
			(layer "F.SilkS")
		)
		(fp_line
			(start -0.12065 -0.305054)
			(end -0.12065 -0.2794)
			(stroke
				(width 0.1)
				(type default)
			)
			(layer "F.Fab")
		)
		(fp_line
			(start -0.67945 -0.305054)
			(end -0.12065 -0.305054)
			(stroke
				(width 0.1)
				(type default)
			)
			(layer "F.Fab")
		)
		(fp_line
			(start 0.67945 -0.3048)
			(end 0.67945 0.3048)
			(stroke
				(width 0.1)
				(type default)
			)
			(layer "F.Fab")
		)
		(fp_line
			(start 0.12065 -0.3048)
			(end 0.67945 -0.3048)
			(stroke
				(width 0.1)
				(type default)
			)
			(layer "F.Fab")
		)
		(fp_line
			(start 0.12065 -0.2794)
			(end 0.12065 -0.3048)
			(stroke
				(width 0.1)
				(type default)
			)
			(layer "F.Fab")
		)
		(fp_line
			(start -0.12065 -0.2794)
			(end 0.12065 -0.2794)
			(stroke
				(width 0.1)
				(type default)
			)
			(layer "F.Fab")
		)
		(fp_line
			(start 0.120396 0.2794)
			(end -0.12065 0.2794)
			(stroke
				(width 0.1)
				(type default)
			)
			(layer "F.Fab")
		)
		(fp_line
			(start -0.12065 0.2794)
			(end -0.12065 0.3048)
			(stroke
				(width 0.1)
				(type default)
			)
			(layer "F.Fab")
		)
		(fp_line
			(start 0.67945 0.3048)
			(end 0.120396 0.3048)
			(stroke
				(width 0.1)
				(type default)
			)
			(layer "F.Fab")
		)
		(fp_line
			(start 0.120396 0.3048)
			(end 0.120396 0.2794)
			(stroke
				(width 0.1)
				(type default)
			)
			(layer "F.Fab")
		)
		(fp_line
			(start -0.12065 0.3048)
			(end -0.67945 0.3048)
			(stroke
				(width 0.1)
				(type default)
			)
			(layer "F.Fab")
		)
		(fp_line
			(start -0.67945 0.3048)
			(end -0.67945 -0.305054)
			(stroke
				(width 0.1)
				(type default)
			)
			(layer "F.Fab")
		)
		(pad "1" smd circle
			(at -0.40005 0 90)
			(size 0 0)
			(layers "F.Cu" "F.Mask" "F.Paste")
			(net "P3V3_AUX")
		)
		(pad "2" smd circle
			(at 0.40005 0 90)
			(size 0 0)
			(layers "F.Cu" "F.Mask" "F.Paste")
			(net "SMB_BMC_MM3_SDA")
		)
	)
	(footprint ""
		(layer "F.Cu")
		(at 84.652612 -37.303456 90)
		(property "Reference" "C291"
			(at 0 0 90)
			(layer "F.SilkS")
			(hide yes)
			(effects
				(font
					(size 1.27 1.27)
				)
			)
		)
		(property "Value" ""
			(at 0 0 90)
			(layer "F.Fab")
			(effects
				(font
					(size 1.27 1.27)
				)
			)
		)
		(duplicate_pad_numbers_are_jumpers no)
		(fp_line
			(start 0.7874 -0.4064)
			(end 0.7874 0.4064)
			(stroke
				(width 0.1524)
				(type default)
			)
			(layer "F.SilkS")
		)
		(fp_line
			(start -0.7874 -0.4064)
			(end 0.7874 -0.4064)
			(stroke
				(width 0.1524)
				(type default)
			)
			(layer "F.SilkS")
		)
		(fp_line
			(start 0.7874 0.4064)
			(end -0.7874 0.4064)
			(stroke
				(width 0.1524)
				(type default)
			)
			(layer "F.SilkS")
		)
		(fp_line
			(start -0.7874 0.4064)
			(end -0.7874 -0.4064)
			(stroke
				(width 0.1524)
				(type default)
			)
			(layer "F.SilkS")
		)
		(fp_line
			(start -0.12065 -0.305054)
			(end -0.12065 -0.2794)
			(stroke
				(width 0.1)
				(type default)
			)
			(layer "F.Fab")
		)
		(fp_line
			(start -0.67945 -0.305054)
			(end -0.12065 -0.305054)
			(stroke
				(width 0.1)
				(type default)
			)
			(layer "F.Fab")
		)
		(fp_line
			(start 0.67945 -0.3048)
			(end 0.67945 0.3048)
			(stroke
				(width 0.1)
				(type default)
			)
			(layer "F.Fab")
		)
		(fp_line
			(start 0.12065 -0.3048)
			(end 0.67945 -0.3048)
			(stroke
				(width 0.1)
				(type default)
			)
			(layer "F.Fab")
		)
		(fp_line
			(start 0.12065 -0.2794)
			(end 0.12065 -0.3048)
			(stroke
				(width 0.1)
				(type default)
			)
			(layer "F.Fab")
		)
		(fp_line
			(start -0.12065 -0.2794)
			(end 0.12065 -0.2794)
			(stroke
				(width 0.1)
				(type default)
			)
			(layer "F.Fab")
		)
		(fp_line
			(start 0.120396 0.2794)
			(end -0.12065 0.2794)
			(stroke
				(width 0.1)
				(type default)
			)
			(layer "F.Fab")
		)
		(fp_line
			(start -0.12065 0.2794)
			(end -0.12065 0.3048)
			(stroke
				(width 0.1)
				(type default)
			)
			(layer "F.Fab")
		)
		(fp_line
			(start 0.67945 0.3048)
			(end 0.120396 0.3048)
			(stroke
				(width 0.1)
				(type default)
			)
			(layer "F.Fab")
		)
		(fp_line
			(start 0.120396 0.3048)
			(end 0.120396 0.2794)
			(stroke
				(width 0.1)
				(type default)
			)
			(layer "F.Fab")
		)
		(fp_line
			(start -0.12065 0.3048)
			(end -0.67945 0.3048)
			(stroke
				(width 0.1)
				(type default)
			)
			(layer "F.Fab")
		)
		(fp_line
			(start -0.67945 0.3048)
			(end -0.67945 -0.305054)
			(stroke
				(width 0.1)
				(type default)
			)
			(layer "F.Fab")
		)
		(pad "1" smd circle
			(at -0.40005 0 90)
			(size 0 0)
			(layers "F.Cu" "F.Mask" "F.Paste")
			(net "P2V5_AUX")
		)
		(pad "2" smd circle
			(at 0.40005 0 90)
			(size 0 0)
			(layers "F.Cu" "F.Mask" "F.Paste")
			(net "GND")
		)
	)
)
